# TIMECARD (Time Appliance Project (Time Card)) — schematic netlist excerpt (pin names and nets, part order shuffled) for the footprints in the layout excerpt that follows; sources: Cadence DE-HDL packaged netlist, KiCad conversion of R4006-B0001-02_R01.brd

C229  CAPACITOR  0.1UF 10V 10%  pkg SMC_0402R_H022  page 31 : \1\ = XP3R3V_FPGA_EN_R ; \2\ = SG
R225  RESISTOR  330OHM 1%  pkg SMC_0402R_H016  page 31 : \1\ = XP1R8V_FPGA_PG ; \2\ = UNNAMED_515_CAPACITOR_I128_1

(kicad_pcb
	(version 20260206)
	(generator "pcbnew")
	(generator_version "10.0")
	(general
		(thickness 1.6)
		(legacy_teardrops no)
	)
	(paper "A4")
	(title_block
		(title "timecard-production-celestica-r4006 — R4006-B0001-02_R01.brd")
		(comment 1 "Time Appliance Project (Time Card) / footprints 1075-1076 of 1113")
	)
	(layers
		(0 "F.Cu" signal "TOP")
		(4 "In1.Cu" signal "L02_GND1")
		(6 "In2.Cu" signal "L03_SIG1")
		(8 "In3.Cu" signal "L04_GND2")
		(10 "In4.Cu" signal "L05_VCC1")
		(12 "In5.Cu" signal "L06_VCC2")
		(14 "In6.Cu" signal "L07_GND3")
		(16 "In7.Cu" signal "L08_SIG2")
		(18 "In8.Cu" signal "L09_GND4")
		(2 "B.Cu" signal "BOTTOM")
		(9 "F.Adhes" user "F.Adhesive")
		(11 "B.Adhes" user "B.Adhesive")
		(13 "F.Paste" user "Package Geometry/Pastemask Top")
		(15 "B.Paste" user "Package Geometry/Pastemask Bottom")
		(5 "F.SilkS" user "Ref Des/Silkscreen Top")
		(7 "B.SilkS" user "Ref Des/Silkscreen Bottom")
		(1 "F.Mask" user "Board Geometry/Soldermask Top")
		(3 "B.Mask" user "Board Geometry/Soldermask Bottom")
		(17 "Dwgs.User" user "User.Drawings")
		(19 "Cmts.User" user "User.Comments")
		(21 "Eco1.User" user "User.Eco1")
		(23 "Eco2.User" user "User.Eco2")
		(25 "Edge.Cuts" user "Board Geometry/Outline")
		(27 "Margin" user)
		(31 "F.CrtYd" user "Package Geometry/Place Bound Top")
		(29 "B.CrtYd" user "Package Geometry/Place Bound Bottom")
		(35 "F.Fab" user "Ref Des/Assembly Top")
		(33 "B.Fab" user "Ref Des/Assembly Bottom")
	)
	(footprint ""
		(layer "B.Cu")
		(at 146.685 -19.685 90)
		(property "Reference" "R225"
			(at 2.794 -0.03937 270)
			(unlocked yes)
			(layer "B.SilkS")
			(effects
				(font
					(size 0.7874 0.5842)
					(thickness 0.1524)
				)
				(justify mirror)
			)
		)
		(property "Value" "VAL*"
			(at -0.02032 2.13233 90)
			(unlocked yes)
			(layer "B.Fab")
			(hide yes)
			(effects
				(font
					(size 0.7874 0.5842)
					(thickness 0.1524)
				)
				(justify mirror)
			)
		)
		(property "Tolerance" "TOL*"
			(at -0.044704 3.05435 90)
			(unlocked yes)
			(layer "Cmts.User")
			(hide yes)
			(effects
				(font
					(size 0.7874 0.5842)
					(thickness 0.1524)
				)
				(justify mirror)
			)
		)
		(property "User Part Number" "PARTNUM*"
			(at -0.02032 4.024884 90)
			(unlocked yes)
			(layer "Cmts.User")
			(hide yes)
			(effects
				(font
					(size 0.7874 0.5842)
					(thickness 0.1524)
				)
				(justify mirror)
			)
		)
		(property "Device Type" "RESISTOR-G155-13300-01,330OHM,A"
			(at -0.008382 1.210564 90)
			(unlocked yes)
			(layer "B.Fab")
			(hide yes)
			(effects
				(font
					(size 0.7874 0.5842)
					(thickness 0.1524)
				)
				(justify mirror)
			)
		)
		(duplicate_pad_numbers_are_jumpers no)
		(fp_line
			(start 1.143 -0.5588)
			(end 1.143 0.5588)
			(stroke
				(width 0.1)
				(type default)
			)
			(layer "B.SilkS")
		)
		(fp_line
			(start -1.143 -0.5588)
			(end 1.143 -0.5588)
			(stroke
				(width 0.1)
				(type default)
			)
			(layer "B.SilkS")
		)
		(fp_line
			(start 1.143 0.5588)
			(end -1.143 0.5588)
			(stroke
				(width 0.1)
				(type default)
			)
			(layer "B.SilkS")
		)
		(fp_line
			(start -1.143 0.5588)
			(end -1.143 -0.5588)
			(stroke
				(width 0.1)
				(type default)
			)
			(layer "B.SilkS")
		)
		(fp_rect
			(start 1.143 -0.5588)
			(end -1.143 0.5588)
			(stroke
				(width 0)
				(type default)
			)
			(fill no)
			(layer "B.CrtYd")
		)
		(fp_line
			(start 0.508 -0.3048)
			(end 0.508 0.3048)
			(stroke
				(width 0.1)
				(type default)
			)
			(layer "B.Fab")
		)
		(fp_line
			(start -0.508 -0.3048)
			(end 0.508 -0.3048)
			(stroke
				(width 0.1)
				(type default)
			)
			(layer "B.Fab")
		)
		(fp_line
			(start 0.508 0.3048)
			(end -0.508 0.3048)
			(stroke
				(width 0.1)
				(type default)
			)
			(layer "B.Fab")
		)
		(fp_line
			(start -0.508 0.3048)
			(end -0.508 -0.3048)
			(stroke
				(width 0.1)
				(type default)
			)
			(layer "B.Fab")
		)
		(pad "1" smd rect
			(at 0.5334 0 270)
			(size 0.7112 0.6096)
			(layers "B.Cu" "B.Mask" "B.Paste")
			(net "XP1R8V_FPGA_PG")
		)
		(pad "2" smd rect
			(at -0.5334 0 270)
			(size 0.7112 0.6096)
			(layers "B.Cu" "B.Mask" "B.Paste")
			(net "UNNAMED_515_CAPACITOR_I128_1")
		)
		(zone
			(layer "B.Cu")
			(hatch none 0.5)
			(connect_pads
				(clearance 0)
			)
			(min_thickness 0.25)
			(keepout
				(tracks allowed)
				(vias not_allowed)
				(pads allowed)
				(copperpour not_allowed)
				(footprints allowed)
			)
			(placement
				(enabled no)
				(sheetname "")
			)
			(fill
				(thermal_gap 0.5)
				(thermal_bridge_width 0.5)
				(island_removal_mode 0)
			)
			(polygon
				(pts
					(xy 146.3802 -19.7612) (xy 146.3802 -19.6088) (xy 146.9898 -19.6088) (xy 146.9898 -19.7612)
				)
			)
		)
	)
	(footprint ""
		(layer "B.Cu")
		(at 115.443 -72.263 180)
		(property "Reference" "C229"
			(at 0.127 -2.45237 0)
			(unlocked yes)
			(layer "B.SilkS")
			(effects
				(font
					(size 0.7874 0.5842)
					(thickness 0.1524)
				)
				(justify mirror)
			)
		)
		(property "Value" "VAL*"
			(at -0.0762 2.067306 180)
			(unlocked yes)
			(layer "B.Fab")
			(hide yes)
			(effects
				(font
					(size 0.7874 0.5842)
					(thickness 0.1524)
				)
				(justify mirror)
			)
		)
		(property "Tolerance" "TOL*"
			(at -0.0762 3.032506 180)
			(unlocked yes)
			(layer "Cmts.User")
			(hide yes)
			(effects
				(font
					(size 0.7874 0.5842)
					(thickness 0.1524)
				)
				(justify mirror)
			)
		)
		(property "User Part Number" "PARTNUM*"
			(at -0.1016 4.023106 180)
			(unlocked yes)
			(layer "Cmts.User")
			(hide yes)
			(effects
				(font
					(size 0.7874 0.5842)
					(thickness 0.1524)
				)
				(justify mirror)
			)
		)
		(property "Device Type" "CAPACITOR-G105-0B104-CK,0.1UF,A"
			(at -0.0508 1.127506 180)
			(unlocked yes)
			(layer "B.Fab")
			(hide yes)
			(effects
				(font
					(size 0.7874 0.5842)
					(thickness 0.1524)
				)
				(justify mirror)
			)
		)
		(duplicate_pad_numbers_are_jumpers no)
		(fp_line
			(start 1.143 0.5588)
			(end -1.143 0.5588)
			(stroke
				(width 0.1)
				(type default)
			)
			(layer "B.SilkS")
		)
		(fp_line
			(start 1.143 -0.5588)
			(end 1.143 0.5588)
			(stroke
				(width 0.1)
				(type default)
			)
			(layer "B.SilkS")
		)
		(fp_line
			(start -1.143 0.5588)
			(end -1.143 -0.5588)
			(stroke
				(width 0.1)
				(type default)
			)
			(layer "B.SilkS")
		)
		(fp_line
			(start -1.143 -0.5588)
			(end 1.143 -0.5588)
			(stroke
				(width 0.1)
				(type default)
			)
			(layer "B.SilkS")
		)
		(fp_rect
			(start 1.143 0.5588)
			(end -1.143 -0.5588)
			(stroke
				(width 0)
				(type default)
			)
			(fill no)
			(layer "B.CrtYd")
		)
		(fp_line
			(start 0.508 0.3048)
			(end -0.508 0.3048)
			(stroke
				(width 0.1)
				(type default)
			)
			(layer "B.Fab")
		)
		(fp_line
			(start 0.508 -0.3048)
			(end 0.508 0.3048)
			(stroke
				(width 0.1)
				(type default)
			)
			(layer "B.Fab")
		)
		(fp_line
			(start -0.508 0.3048)
			(end -0.508 -0.3048)
			(stroke
				(width 0.1)
				(type default)
			)
			(layer "B.Fab")
		)
		(fp_line
			(start -0.508 -0.3048)
			(end 0.508 -0.3048)
			(stroke
				(width 0.1)
				(type default)
			)
			(layer "B.Fab")
		)
		(pad "1" smd rect
			(at 0.5334 0)
			(size 0.7112 0.6096)
			(layers "B.Cu" "B.Mask" "B.Paste")
			(net "XP3R3V_FPGA_EN_R")
		)
		(pad "2" smd rect
			(at -0.5334 0)
			(size 0.7112 0.6096)
			(layers "B.Cu" "B.Mask" "B.Paste")
			(net "SG")
		)
		(zone
			(layer "B.Cu")
			(hatch none 0.5)
			(connect_pads
				(clearance 0)
			)
			(min_thickness 0.25)
			(keepout
				(tracks allowed)
				(vias not_allowed)
				(pads allowed)
				(copperpour not_allowed)
				(footprints allowed)
			)
			(placement
				(enabled no)
				(sheetname "")
			)
			(fill
				(thermal_gap 0.5)
				(thermal_bridge_width 0.5)
				(island_removal_mode 0)
			)
			(polygon
				(pts
					(xy 115.3668 -72.5678) (xy 115.3668 -71.9582) (xy 115.5192 -71.9582) (xy 115.5192 -72.5678)
				)
			)
		)
	)
)
